# S9S_MB_2U (Grand Teton) — schematic netlist excerpt (pin names and nets, part order shuffled) for the footprints in the layout excerpt that follows; sources: Cadence DE-HDL packaged netlist, KiCad conversion of 03242023_DA0F0TMBIJ0_F0T_Motherboard_J_brd_V01_OCP.brd

PR148  Q_RES  0 5% CHIP  pkg 0402LF  page 268 : A = PVCCIN_CPU0_VOS4 ; B = PVCCIN_CPU0
C342  Q_CAP  47UF 4V 20% X6S  pkg C0805  page 79 : A = PVCCIN_CPU1 ; B = GND
R4284  Q_RES  1K 1% EMPTY  pkg 0402LF  page 169 : A = P3V3_AUX ; B = FM_USB3_1_SWB

(kicad_pcb
	(version 20260206)
	(generator "pcbnew")
	(generator_version "10.0")
	(general
		(thickness 1.6)
		(legacy_teardrops no)
	)
	(paper "A4")
	(title_block
		(title "03242023_DA0F0TMBIJ0_F0T_Motherboard_J_brd_V01_OCP.brd")
		(comment 1 "Grand Teton / footprints 4712-4714 of 6105")
	)
	(layers
		(0 "F.Cu" signal "TOP")
		(4 "In1.Cu" signal "GND")
		(6 "In2.Cu" signal "IN1")
		(8 "In3.Cu" signal "GND1")
		(10 "In4.Cu" signal "IN2")
		(12 "In5.Cu" signal "GND2")
		(14 "In6.Cu" signal "IN3")
		(16 "In7.Cu" signal "GND3")
		(18 "In8.Cu" signal "VCC")
		(20 "In9.Cu" signal "VCC1")
		(22 "In10.Cu" signal "GND4")
		(24 "In11.Cu" signal "IN4")
		(26 "In12.Cu" signal "GND5")
		(28 "In13.Cu" signal "IN5")
		(30 "In14.Cu" signal "GND6")
		(32 "In15.Cu" signal "IN6")
		(34 "In16.Cu" signal "GND7")
		(2 "B.Cu" signal "BOTTOM")
		(9 "F.Adhes" user "F.Adhesive")
		(11 "B.Adhes" user "B.Adhesive")
		(13 "F.Paste" user "Package Geometry/Pastemask Top")
		(15 "B.Paste" user "Package Geometry/Pastemask Bottom")
		(5 "F.SilkS" user "Ref Des/Silkscreen Top")
		(7 "B.SilkS" user "Ref Des/Silkscreen Bottom")
		(1 "F.Mask" user "Board Geometry/Soldermask Top")
		(3 "B.Mask" user "Board Geometry/Soldermask Bottom")
		(17 "Dwgs.User" user "User.Drawings")
		(19 "Cmts.User" user "User.Comments")
		(21 "Eco1.User" user "User.Eco1")
		(23 "Eco2.User" user "User.Eco2")
		(25 "Edge.Cuts" user "Board Geometry/Outline")
		(27 "Margin" user)
		(31 "F.CrtYd" user "Package Geometry/Place Bound Top")
		(29 "B.CrtYd" user "Package Geometry/Place Bound Bottom")
		(35 "F.Fab" user "Ref Des/Assembly Top")
		(33 "B.Fab" user "Ref Des/Assembly Bottom")
	)
	(footprint ""
		(layer "B.Cu")
		(at 366.450372 -337.899248)
		(property "Reference" "PR148"
			(at 0 0 0)
			(layer "B.SilkS")
			(hide yes)
			(effects
				(font
					(size 1.27 1.27)
				)
				(justify mirror)
			)
		)
		(property "Value" ""
			(at 0 0 0)
			(layer "B.Fab")
			(effects
				(font
					(size 1.27 1.27)
				)
				(justify mirror)
			)
		)
		(duplicate_pad_numbers_are_jumpers no)
		(fp_line
			(start -0.7874 -0.4064)
			(end -0.7874 0.4064)
			(stroke
				(width 0.1524)
				(type default)
			)
			(layer "B.SilkS")
		)
		(fp_line
			(start -0.7874 0.4064)
			(end 0.7874 0.4064)
			(stroke
				(width 0.1524)
				(type default)
			)
			(layer "B.SilkS")
		)
		(fp_line
			(start 0.7874 -0.4064)
			(end -0.7874 -0.4064)
			(stroke
				(width 0.1524)
				(type default)
			)
			(layer "B.SilkS")
		)
		(fp_line
			(start 0.7874 0.4064)
			(end 0.7874 -0.4064)
			(stroke
				(width 0.1524)
				(type default)
			)
			(layer "B.SilkS")
		)
		(fp_line
			(start -0.67945 -0.3048)
			(end -0.67945 0.3048)
			(stroke
				(width 0.1)
				(type default)
			)
			(layer "B.Fab")
		)
		(fp_line
			(start -0.67945 0.3048)
			(end -0.120396 0.3048)
			(stroke
				(width 0.1)
				(type default)
			)
			(layer "B.Fab")
		)
		(fp_line
			(start -0.12065 -0.3048)
			(end -0.67945 -0.3048)
			(stroke
				(width 0.1)
				(type default)
			)
			(layer "B.Fab")
		)
		(fp_line
			(start -0.12065 -0.2794)
			(end -0.12065 -0.3048)
			(stroke
				(width 0.1)
				(type default)
			)
			(layer "B.Fab")
		)
		(fp_line
			(start -0.120396 0.2794)
			(end 0.12065 0.2794)
			(stroke
				(width 0.1)
				(type default)
			)
			(layer "B.Fab")
		)
		(fp_line
			(start -0.120396 0.3048)
			(end -0.120396 0.2794)
			(stroke
				(width 0.1)
				(type default)
			)
			(layer "B.Fab")
		)
		(fp_line
			(start 0.12065 -0.305054)
			(end 0.12065 -0.2794)
			(stroke
				(width 0.1)
				(type default)
			)
			(layer "B.Fab")
		)
		(fp_line
			(start 0.12065 -0.2794)
			(end -0.12065 -0.2794)
			(stroke
				(width 0.1)
				(type default)
			)
			(layer "B.Fab")
		)
		(fp_line
			(start 0.12065 0.2794)
			(end 0.12065 0.3048)
			(stroke
				(width 0.1)
				(type default)
			)
			(layer "B.Fab")
		)
		(fp_line
			(start 0.12065 0.3048)
			(end 0.67945 0.3048)
			(stroke
				(width 0.1)
				(type default)
			)
			(layer "B.Fab")
		)
		(fp_line
			(start 0.67945 -0.305054)
			(end 0.12065 -0.305054)
			(stroke
				(width 0.1)
				(type default)
			)
			(layer "B.Fab")
		)
		(fp_line
			(start 0.67945 0.3048)
			(end 0.67945 -0.305054)
			(stroke
				(width 0.1)
				(type default)
			)
			(layer "B.Fab")
		)
		(pad "1" smd circle
			(at 0.40005 0 180)
			(size 0 0)
			(layers "B.Cu" "B.Mask" "B.Paste")
			(net "PVCCIN_CPU0_VOS4")
		)
		(pad "2" smd circle
			(at -0.40005 0 180)
			(size 0 0)
			(layers "B.Cu" "B.Mask" "B.Paste")
			(net "PVCCIN_CPU0")
		)
	)
	(footprint ""
		(layer "B.Cu")
		(at 127.83058 -31.529528 90)
		(property "Reference" "R4284"
			(at 0 0 90)
			(layer "B.SilkS")
			(hide yes)
			(effects
				(font
					(size 1.27 1.27)
				)
				(justify mirror)
			)
		)
		(property "Value" ""
			(at 0 0 90)
			(layer "B.Fab")
			(effects
				(font
					(size 1.27 1.27)
				)
				(justify mirror)
			)
		)
		(duplicate_pad_numbers_are_jumpers no)
		(fp_line
			(start 0.7874 -0.4064)
			(end -0.7874 -0.4064)
			(stroke
				(width 0.1524)
				(type default)
			)
			(layer "B.SilkS")
		)
		(fp_line
			(start -0.7874 -0.4064)
			(end -0.7874 0.4064)
			(stroke
				(width 0.1524)
				(type default)
			)
			(layer "B.SilkS")
		)
		(fp_line
			(start 0.7874 0.4064)
			(end 0.7874 -0.4064)
			(stroke
				(width 0.1524)
				(type default)
			)
			(layer "B.SilkS")
		)
		(fp_line
			(start -0.7874 0.4064)
			(end 0.7874 0.4064)
			(stroke
				(width 0.1524)
				(type default)
			)
			(layer "B.SilkS")
		)
		(fp_line
			(start 0.67945 -0.305054)
			(end 0.12065 -0.305054)
			(stroke
				(width 0.1)
				(type default)
			)
			(layer "B.Fab")
		)
		(fp_line
			(start 0.12065 -0.305054)
			(end 0.12065 -0.2794)
			(stroke
				(width 0.1)
				(type default)
			)
			(layer "B.Fab")
		)
		(fp_line
			(start -0.12065 -0.3048)
			(end -0.67945 -0.3048)
			(stroke
				(width 0.1)
				(type default)
			)
			(layer "B.Fab")
		)
		(fp_line
			(start -0.67945 -0.3048)
			(end -0.67945 0.3048)
			(stroke
				(width 0.1)
				(type default)
			)
			(layer "B.Fab")
		)
		(fp_line
			(start 0.12065 -0.2794)
			(end -0.12065 -0.2794)
			(stroke
				(width 0.1)
				(type default)
			)
			(layer "B.Fab")
		)
		(fp_line
			(start -0.12065 -0.2794)
			(end -0.12065 -0.3048)
			(stroke
				(width 0.1)
				(type default)
			)
			(layer "B.Fab")
		)
		(fp_line
			(start 0.12065 0.2794)
			(end 0.12065 0.3048)
			(stroke
				(width 0.1)
				(type default)
			)
			(layer "B.Fab")
		)
		(fp_line
			(start -0.120396 0.2794)
			(end 0.12065 0.2794)
			(stroke
				(width 0.1)
				(type default)
			)
			(layer "B.Fab")
		)
		(fp_line
			(start 0.67945 0.3048)
			(end 0.67945 -0.305054)
			(stroke
				(width 0.1)
				(type default)
			)
			(layer "B.Fab")
		)
		(fp_line
			(start 0.12065 0.3048)
			(end 0.67945 0.3048)
			(stroke
				(width 0.1)
				(type default)
			)
			(layer "B.Fab")
		)
		(fp_line
			(start -0.120396 0.3048)
			(end -0.120396 0.2794)
			(stroke
				(width 0.1)
				(type default)
			)
			(layer "B.Fab")
		)
		(fp_line
			(start -0.67945 0.3048)
			(end -0.120396 0.3048)
			(stroke
				(width 0.1)
				(type default)
			)
			(layer "B.Fab")
		)
		(pad "1" smd circle
			(at 0.40005 0 270)
			(size 0 0)
			(layers "B.Cu" "B.Mask" "B.Paste")
			(net "P3V3_AUX")
		)
		(pad "2" smd circle
			(at -0.40005 0 270)
			(size 0 0)
			(layers "B.Cu" "B.Mask" "B.Paste")
			(net "FM_USB3_1_SWB")
		)
	)
	(footprint ""
		(layer "B.Cu")
		(at 102.495604 -296.05478 180)
		(property "Reference" "C342"
			(at 0 0 0)
			(layer "B.SilkS")
			(hide yes)
			(effects
				(font
					(size 1.27 1.27)
				)
				(justify mirror)
			)
		)
		(property "Value" ""
			(at 0 0 0)
			(layer "B.Fab")
			(effects
				(font
					(size 1.27 1.27)
				)
				(justify mirror)
			)
		)
		(duplicate_pad_numbers_are_jumpers no)
		(fp_line
			(start 1.524 0.762)
			(end 1.524 -0.762)
			(stroke
				(width 0.1524)
				(type default)
			)
			(layer "B.SilkS")
		)
		(fp_line
			(start 1.524 -0.762)
			(end -1.524 -0.762)
			(stroke
				(width 0.1524)
				(type default)
			)
			(layer "B.SilkS")
		)
		(fp_line
			(start -1.524 0.762)
			(end 1.524 0.762)
			(stroke
				(width 0.1524)
				(type default)
			)
			(layer "B.SilkS")
		)
		(fp_line
			(start -1.524 -0.762)
			(end -1.524 0.762)
			(stroke
				(width 0.1524)
				(type default)
			)
			(layer "B.SilkS")
		)
		(fp_line
			(start 1.1049 0.724916)
			(end -1.1049 0.724916)
			(stroke
				(width 0.1)
				(type default)
			)
			(layer "B.Fab")
		)
		(fp_line
			(start 1.1049 -0.724916)
			(end 1.1049 0.724916)
			(stroke
				(width 0.1)
				(type default)
			)
			(layer "B.Fab")
		)
		(fp_line
			(start -1.1049 0.724916)
			(end -1.1049 -0.724916)
			(stroke
				(width 0.1)
				(type default)
			)
			(layer "B.Fab")
		)
		(fp_line
			(start -1.1049 -0.724916)
			(end 1.1049 -0.724916)
			(stroke
				(width 0.1)
				(type default)
			)
			(layer "B.Fab")
		)
		(pad "1" smd rect
			(at 0.889 0 180)
			(size 1.016 1.27)
			(layers "B.Cu" "B.Mask" "B.Paste")
			(net "PVCCIN_CPU1")
		)
		(pad "2" smd rect
			(at -0.889 0 180)
			(size 1.016 1.27)
			(layers "B.Cu" "B.Mask" "B.Paste")
			(net "GND")
		)
	)
)
